(kicad_pcb
	(version 20260206)
	(generator "pcbnew")
	(generator_version "10.0")
	(general
		(thickness 1.6)
		(legacy_teardrops no)
	)
	(paper "A4")
	(title_block
		(title "Bryce Canyon_F.DPB_16315-1-OCP.brd")
		(comment 1 "Bryce Canyon / footprints 470-477 of 2223")
	)
	(layers
		(0 "F.Cu" signal "TOP")
		(4 "In1.Cu" signal "L2GND")
		(6 "In2.Cu" signal "L3")
		(8 "In3.Cu" signal "L4GND")
		(10 "In4.Cu" signal "L5")
		(12 "In5.Cu" signal "L6VCC")
		(14 "In6.Cu" signal "L7VCC")
		(16 "In7.Cu" signal "L8")
		(18 "In8.Cu" signal "L9GND")
		(20 "In9.Cu" signal "L10")
		(22 "In10.Cu" signal "L11GND")
		(2 "B.Cu" signal "BOTTOM")
		(9 "F.Adhes" user "F.Adhesive")
		(11 "B.Adhes" user "B.Adhesive")
		(13 "F.Paste" user "Package Geometry/Pastemask Top")
		(15 "B.Paste" user "Package Geometry/Pastemask Bottom")
		(5 "F.SilkS" user "Ref Des/Silkscreen Top")
		(7 "B.SilkS" user "Ref Des/Silkscreen Bottom")
		(1 "F.Mask" user "Board Geometry/Soldermask Top")
		(3 "B.Mask" user "Board Geometry/Soldermask Bottom")
		(17 "Dwgs.User" user "User.Drawings")
		(19 "Cmts.User" user "User.Comments")
		(21 "Eco1.User" user "User.Eco1")
		(23 "Eco2.User" user "User.Eco2")
		(25 "Edge.Cuts" user "Board Geometry/Outline")
		(27 "Margin" user)
		(31 "F.CrtYd" user "Package Geometry/Place Bound Top")
		(29 "B.CrtYd" user "Package Geometry/Place Bound Bottom")
		(35 "F.Fab" user "Ref Des/Assembly Top")
		(33 "B.Fab" user "Ref Des/Assembly Bottom")
	)
	(footprint ""
		(layer "F.Cu")
		(at 333.329534 -21.88337 90)
		(property "Reference" "R79"
			(at 0 0 90)
			(layer "F.SilkS")
			(hide yes)
			(effects
				(font
					(size 1.27 1.27)
				)
			)
		)
		(property "Value" "4K7R2F-GP"
			(at 0.064008 -3.993896 90)
			(unlocked yes)
			(layer "F.Fab")
			(hide yes)
			(effects
				(font
					(size 1.016 1.016)
					(thickness 0.1524)
				)
			)
		)
		(property "Device Type" "R402H16"
			(at 0.064008 -5.517896 90)
			(unlocked yes)
			(layer "F.Fab")
			(hide yes)
			(effects
				(font
					(size 1.016 1.016)
					(thickness 0.1524)
				)
			)
		)
		(duplicate_pad_numbers_are_jumpers no)
		(fp_line
			(start 0.508 -0.9398)
			(end -0.508 -0.9398)
			(stroke
				(width 0.1524)
				(type default)
			)
			(layer "F.SilkS")
		)
		(fp_line
			(start -0.508 -0.9398)
			(end -0.508 0.9398)
			(stroke
				(width 0.1524)
				(type default)
			)
			(layer "F.SilkS")
		)
		(fp_rect
			(start -0.508 0.9398)
			(end 0.508 -0.9398)
			(stroke
				(width 0)
				(type default)
			)
			(fill no)
			(layer "F.CrtYd")
		)
		(fp_rect
			(start -0.508 0.9398)
			(end 0.508 -0.9398)
			(stroke
				(width 0)
				(type default)
			)
			(fill no)
			(layer "F.Fab")
		)
		(pad "1" smd custom
			(at 0 -0.4445 90)
			(size 0.1397 0.1397)
			(layers "F.Cu" "F.Mask" "F.Paste")
			(net "P3V3_STBY_B")
			(options
				(clearance outline)
				(anchor circle)
			)
			(primitives
				(gr_poly
					(pts
						(arc
							(start -0.1778 -0.2794)
							(mid -0.249642 -0.249642)
							(end -0.2794 -0.1778)
						)
						(arc
							(start -0.2794 0.1778)
							(mid -0.249642 0.249642)
							(end -0.1778 0.2794)
						)
						(arc
							(start 0.1778 0.2794)
							(mid 0.249642 0.249642)
							(end 0.2794 0.1778)
						)
						(arc
							(start 0.2794 -0.1778)
							(mid 0.249642 -0.249642)
							(end 0.1778 -0.2794)
						)
					)
					(width 0)
					(fill yes)
				)
			)
		)
		(pad "2" smd custom
			(at 0 0.4445 90)
			(size 0.1397 0.1397)
			(layers "F.Cu" "F.Mask" "F.Paste")
			(net "IO_EXP11_A1")
			(options
				(clearance outline)
				(anchor circle)
			)
			(primitives
				(gr_poly
					(pts
						(arc
							(start -0.1778 -0.2794)
							(mid -0.249642 -0.249642)
							(end -0.2794 -0.1778)
						)
						(arc
							(start -0.2794 0.1778)
							(mid -0.249642 0.249642)
							(end -0.1778 0.2794)
						)
						(arc
							(start 0.1778 0.2794)
							(mid 0.249642 0.249642)
							(end 0.2794 0.1778)
						)
						(arc
							(start 0.2794 -0.1778)
							(mid 0.249642 -0.249642)
							(end 0.1778 -0.2794)
						)
					)
					(width 0)
					(fill yes)
				)
			)
		)
	)
	(footprint ""
		(layer "F.Cu")
		(at 47.866046 -284.371542 -90)
		(property "Reference" "R167"
			(at 0 0 270)
			(layer "F.SilkS")
			(hide yes)
			(effects
				(font
					(size 1.27 1.27)
				)
			)
		)
		(property "Value" "300KR2F-GP"
			(at 0.064008 -3.993896 270)
			(unlocked yes)
			(layer "F.Fab")
			(hide yes)
			(effects
				(font
					(size 1.016 1.016)
					(thickness 0.1524)
				)
			)
		)
		(property "Device Type" "R402H16"
			(at 0.064008 -5.517896 270)
			(unlocked yes)
			(layer "F.Fab")
			(hide yes)
			(effects
				(font
					(size 1.016 1.016)
					(thickness 0.1524)
				)
			)
		)
		(duplicate_pad_numbers_are_jumpers no)
		(fp_line
			(start -0.508 -0.9398)
			(end -0.508 0.9398)
			(stroke
				(width 0.1524)
				(type default)
			)
			(layer "F.SilkS")
		)
		(fp_line
			(start 0.508 -0.9398)
			(end -0.508 -0.9398)
			(stroke
				(width 0.1524)
				(type default)
			)
			(layer "F.SilkS")
		)
		(fp_rect
			(start -0.508 0.9398)
			(end 0.508 -0.9398)
			(stroke
				(width 0)
				(type default)
			)
			(fill no)
			(layer "F.CrtYd")
		)
		(fp_rect
			(start -0.508 0.9398)
			(end 0.508 -0.9398)
			(stroke
				(width 0)
				(type default)
			)
			(fill no)
			(layer "F.Fab")
		)
		(pad "1" smd custom
			(at 0 -0.4445 270)
			(size 0.1397 0.1397)
			(layers "F.Cu" "F.Mask" "F.Paste")
			(net "SW_HDD_N1")
			(options
				(clearance outline)
				(anchor circle)
			)
			(primitives
				(gr_poly
					(pts
						(arc
							(start -0.1778 -0.2794)
							(mid -0.249642 -0.249642)
							(end -0.2794 -0.1778)
						)
						(arc
							(start -0.2794 0.1778)
							(mid -0.249642 0.249642)
							(end -0.1778 0.2794)
						)
						(arc
							(start 0.1778 0.2794)
							(mid 0.249642 0.249642)
							(end 0.2794 0.1778)
						)
						(arc
							(start 0.2794 -0.1778)
							(mid 0.249642 -0.249642)
							(end 0.1778 -0.2794)
						)
					)
					(width 0)
					(fill yes)
				)
			)
		)
		(pad "2" smd custom
			(at 0 0.4445 270)
			(size 0.1397 0.1397)
			(layers "F.Cu" "F.Mask" "F.Paste")
			(net "P12V_A")
			(options
				(clearance outline)
				(anchor circle)
			)
			(primitives
				(gr_poly
					(pts
						(arc
							(start -0.1778 -0.2794)
							(mid -0.249642 -0.249642)
							(end -0.2794 -0.1778)
						)
						(arc
							(start -0.2794 0.1778)
							(mid -0.249642 0.249642)
							(end -0.1778 0.2794)
						)
						(arc
							(start 0.1778 0.2794)
							(mid 0.249642 0.249642)
							(end 0.2794 0.1778)
						)
						(arc
							(start 0.2794 -0.1778)
							(mid 0.249642 -0.249642)
							(end 0.1778 -0.2794)
						)
					)
					(width 0)
					(fill yes)
				)
			)
		)
	)
	(footprint ""
		(layer "F.Cu")
		(at 38.763448 -294.191182 90)
		(property "Reference" "R554"
			(at 0 0 90)
			(layer "F.SilkS")
			(hide yes)
			(effects
				(font
					(size 1.27 1.27)
				)
			)
		)
		(property "Value" "4K7R2J-2-GP"
			(at 0.064008 -3.993896 90)
			(unlocked yes)
			(layer "F.Fab")
			(hide yes)
			(effects
				(font
					(size 1.016 1.016)
					(thickness 0.1524)
				)
			)
		)
		(property "Device Type" "R402H16"
			(at 0.064008 -5.517896 90)
			(unlocked yes)
			(layer "F.Fab")
			(hide yes)
			(effects
				(font
					(size 1.016 1.016)
					(thickness 0.1524)
				)
			)
		)
		(duplicate_pad_numbers_are_jumpers no)
		(fp_line
			(start 0.508 -0.9398)
			(end -0.508 -0.9398)
			(stroke
				(width 0.1524)
				(type default)
			)
			(layer "F.SilkS")
		)
		(fp_line
			(start -0.508 -0.9398)
			(end -0.508 0.9398)
			(stroke
				(width 0.1524)
				(type default)
			)
			(layer "F.SilkS")
		)
		(fp_rect
			(start -0.508 0.9398)
			(end 0.508 -0.9398)
			(stroke
				(width 0)
				(type default)
			)
			(fill no)
			(layer "F.CrtYd")
		)
		(fp_rect
			(start -0.508 0.9398)
			(end 0.508 -0.9398)
			(stroke
				(width 0)
				(type default)
			)
			(fill no)
			(layer "F.Fab")
		)
		(pad "1" smd custom
			(at 0 -0.4445 90)
			(size 0.1397 0.1397)
			(layers "F.Cu" "F.Mask" "F.Paste")
			(net "DRIVE_B_25_ACT")
			(options
				(clearance outline)
				(anchor circle)
			)
			(primitives
				(gr_poly
					(pts
						(arc
							(start -0.1778 -0.2794)
							(mid -0.249642 -0.249642)
							(end -0.2794 -0.1778)
						)
						(arc
							(start -0.2794 0.1778)
							(mid -0.249642 0.249642)
							(end -0.1778 0.2794)
						)
						(arc
							(start 0.1778 0.2794)
							(mid 0.249642 0.249642)
							(end 0.2794 0.1778)
						)
						(arc
							(start 0.2794 -0.1778)
							(mid 0.249642 -0.249642)
							(end 0.1778 -0.2794)
						)
					)
					(width 0)
					(fill yes)
				)
			)
		)
		(pad "2" smd custom
			(at 0 0.4445 90)
			(size 0.1397 0.1397)
			(layers "F.Cu" "F.Mask" "F.Paste")
			(net "GND")
			(options
				(clearance outline)
				(anchor circle)
			)
			(primitives
				(gr_poly
					(pts
						(arc
							(start -0.1778 -0.2794)
							(mid -0.249642 -0.249642)
							(end -0.2794 -0.1778)
						)
						(arc
							(start -0.2794 0.1778)
							(mid -0.249642 0.249642)
							(end -0.1778 0.2794)
						)
						(arc
							(start 0.1778 0.2794)
							(mid 0.249642 0.249642)
							(end 0.2794 0.1778)
						)
						(arc
							(start 0.2794 -0.1778)
							(mid 0.249642 -0.249642)
							(end 0.1778 -0.2794)
						)
					)
					(width 0)
					(fill yes)
				)
			)
		)
	)
	(footprint ""
		(layer "F.Cu")
		(at 471.980514 -280.158698 -90)
		(property "Reference" "C191"
			(at 0 0 270)
			(layer "F.SilkS")
			(hide yes)
			(effects
				(font
					(size 1.27 1.27)
				)
			)
		)
		(property "Value" "SCD033U25V2KX-GP"
			(at 1.1811 -2.7051 270)
			(unlocked yes)
			(layer "F.Fab")
			(hide yes)
			(effects
				(font
					(size 1.016 1.016)
					(thickness 0.1524)
				)
			)
		)
		(property "Device Type" "C402H22"
			(at 1.1811 -4.2291 270)
			(unlocked yes)
			(layer "F.Fab")
			(hide yes)
			(effects
				(font
					(size 1.016 1.016)
					(thickness 0.1524)
				)
			)
		)
		(duplicate_pad_numbers_are_jumpers no)
		(fp_rect
			(start -0.4318 0.9525)
			(end 0.4318 -0.9525)
			(stroke
				(width 0)
				(type default)
			)
			(fill no)
			(layer "F.CrtYd")
		)
		(fp_rect
			(start -0.4318 0.9525)
			(end 0.4318 -0.9525)
			(stroke
				(width 0)
				(type default)
			)
			(fill no)
			(layer "F.Fab")
		)
		(pad "1" smd custom
			(at 0 -0.4445 270)
			(size 0.1524 0.1524)
			(layers "F.Cu" "F.Mask" "F.Paste")
			(net "SW_HDD_P11")
			(options
				(clearance outline)
				(anchor circle)
			)
			(primitives
				(gr_poly
					(pts
						(arc
							(start 0.3048 -0.2032)
							(mid 0.275042 -0.275042)
							(end 0.2032 -0.3048)
						)
						(arc
							(start -0.2032 -0.3048)
							(mid -0.275042 -0.275042)
							(end -0.3048 -0.2032)
						)
						(arc
							(start -0.3048 0.2032)
							(mid -0.275042 0.275042)
							(end -0.2032 0.3048)
						)
						(arc
							(start 0.2032 0.3048)
							(mid 0.275042 0.275042)
							(end 0.3048 0.2032)
						)
					)
					(width 0)
					(fill yes)
				)
			)
		)
		(pad "2" smd custom
			(at 0 0.4445 270)
			(size 0.1524 0.1524)
			(layers "F.Cu" "F.Mask" "F.Paste")
			(net "GND")
			(options
				(clearance outline)
				(anchor circle)
			)
			(primitives
				(gr_poly
					(pts
						(arc
							(start 0.3048 -0.2032)
							(mid 0.275042 -0.275042)
							(end 0.2032 -0.3048)
						)
						(arc
							(start -0.2032 -0.3048)
							(mid -0.275042 -0.275042)
							(end -0.3048 -0.2032)
						)
						(arc
							(start -0.3048 0.2032)
							(mid -0.275042 0.275042)
							(end -0.2032 0.3048)
						)
						(arc
							(start 0.2032 0.3048)
							(mid 0.275042 0.275042)
							(end 0.3048 0.2032)
						)
					)
					(width 0)
					(fill yes)
				)
			)
		)
	)
	(footprint ""
		(layer "F.Cu")
		(at 77.815948 -64.683894 -90)
		(property "Reference" "C382"
			(at 0 0 270)
			(layer "F.SilkS")
			(hide yes)
			(effects
				(font
					(size 1.27 1.27)
				)
			)
		)
		(property "Value" "SC4D7U25V5KX-1-GP"
			(at -0.0762 -6.1214 270)
			(unlocked yes)
			(layer "F.Fab")
			(hide yes)
			(effects
				(font
					(size 1.016 1.016)
					(thickness 0.1524)
				)
			)
		)
		(property "Device Type" "C805H58"
			(at -0.0762 -8.1534 270)
			(unlocked yes)
			(layer "F.Fab")
			(hide yes)
			(effects
				(font
					(size 1.016 1.016)
					(thickness 0.1524)
				)
			)
		)
		(duplicate_pad_numbers_are_jumpers no)
		(fp_line
			(start 0.635 0)
			(end -0.635 0)
			(stroke
				(width 0.508)
				(type default)
			)
			(layer "F.SilkS")
		)
		(fp_rect
			(start -0.9652 1.778)
			(end 0.9652 -1.778)
			(stroke
				(width 0)
				(type default)
			)
			(fill no)
			(layer "F.CrtYd")
		)
		(fp_poly
			(pts
				(xy -0.9652 -1.778) (xy 0.9652 -1.778) (xy 0.9652 1.778) (xy -0.9652 1.778)
			)
			(stroke
				(width 0)
				(type default)
			)
			(fill no)
			(layer "F.Fab")
		)
		(pad "1" smd rect
			(at 0 -0.9652 270)
			(size 1.397 1.143)
			(layers "F.Cu" "F.Mask" "F.Paste")
			(net "P12V_HDD26")
		)
		(pad "2" smd rect
			(at 0 0.9652 270)
			(size 1.397 1.143)
			(layers "F.Cu" "F.Mask" "F.Paste")
			(net "GND")
		)
	)
	(footprint ""
		(layer "F.Cu")
		(at 298.7802 -74.7776)
		(property "Reference" "R370"
			(at 0 0 0)
			(layer "F.SilkS")
			(hide yes)
			(effects
				(font
					(size 1.27 1.27)
				)
			)
		)
		(property "Value" "4K7R2F-GP"
			(at 0.064008 -3.993896 0)
			(unlocked yes)
			(layer "F.Fab")
			(hide yes)
			(effects
				(font
					(size 1.016 1.016)
					(thickness 0.1524)
				)
			)
		)
		(property "Device Type" "R402H16"
			(at 0.064008 -5.517896 0)
			(unlocked yes)
			(layer "F.Fab")
			(hide yes)
			(effects
				(font
					(size 1.016 1.016)
					(thickness 0.1524)
				)
			)
		)
		(duplicate_pad_numbers_are_jumpers no)
		(fp_line
			(start -0.508 -0.9398)
			(end -0.508 0.9398)
			(stroke
				(width 0.1524)
				(type default)
			)
			(layer "F.SilkS")
		)
		(fp_line
			(start 0.508 -0.9398)
			(end -0.508 -0.9398)
			(stroke
				(width 0.1524)
				(type default)
			)
			(layer "F.SilkS")
		)
		(fp_rect
			(start -0.508 0.9398)
			(end 0.508 -0.9398)
			(stroke
				(width 0)
				(type default)
			)
			(fill no)
			(layer "F.CrtYd")
		)
		(fp_rect
			(start -0.508 0.9398)
			(end 0.508 -0.9398)
			(stroke
				(width 0)
				(type default)
			)
			(fill no)
			(layer "F.Fab")
		)
		(pad "1" smd custom
			(at 0 -0.4445)
			(size 0.1397 0.1397)
			(layers "F.Cu" "F.Mask" "F.Paste")
			(net "COMP_B_POWER_FAIL_N")
			(options
				(clearance outline)
				(anchor circle)
			)
			(primitives
				(gr_poly
					(pts
						(arc
							(start -0.1778 -0.2794)
							(mid -0.249642 -0.249642)
							(end -0.2794 -0.1778)
						)
						(arc
							(start -0.2794 0.1778)
							(mid -0.249642 0.249642)
							(end -0.1778 0.2794)
						)
						(arc
							(start 0.1778 0.2794)
							(mid 0.249642 0.249642)
							(end 0.2794 0.1778)
						)
						(arc
							(start 0.2794 -0.1778)
							(mid 0.249642 -0.249642)
							(end 0.1778 -0.2794)
						)
					)
					(width 0)
					(fill yes)
				)
			)
		)
		(pad "2" smd custom
			(at 0 0.4445)
			(size 0.1397 0.1397)
			(layers "F.Cu" "F.Mask" "F.Paste")
			(net "P3V3_STBY_B")
			(options
				(clearance outline)
				(anchor circle)
			)
			(primitives
				(gr_poly
					(pts
						(arc
							(start -0.1778 -0.2794)
							(mid -0.249642 -0.249642)
							(end -0.2794 -0.1778)
						)
						(arc
							(start -0.2794 0.1778)
							(mid -0.249642 0.249642)
							(end -0.1778 0.2794)
						)
						(arc
							(start 0.1778 0.2794)
							(mid 0.249642 0.249642)
							(end 0.2794 0.1778)
						)
						(arc
							(start 0.2794 -0.1778)
							(mid 0.249642 -0.249642)
							(end 0.1778 -0.2794)
						)
					)
					(width 0)
					(fill yes)
				)
			)
		)
	)
	(footprint ""
		(layer "F.Cu")
		(at 431.962052 -277.792942 90)
		(property "Reference" "D9"
			(at 0 0 90)
			(layer "F.SilkS")
			(hide yes)
			(effects
				(font
					(size 1.27 1.27)
				)
			)
		)
		(property "Value" "RB551V30-GP"
			(at 0 -6.7818 90)
			(unlocked yes)
			(layer "F.Fab")
			(hide yes)
			(effects
				(font
					(size 1.016 1.016)
					(thickness 0.1524)
				)
			)
		)
		(property "Device Type" "SOD323AKH38"
			(at 0 -8.6868 90)
			(unlocked yes)
			(layer "F.Fab")
			(hide yes)
			(effects
				(font
					(size 1.016 1.016)
					(thickness 0.1524)
				)
			)
		)
		(duplicate_pad_numbers_are_jumpers no)
		(fp_line
			(start 0.889 -1.9304)
			(end 0.889 2.159)
			(stroke
				(width 0.1524)
				(type default)
			)
			(layer "F.SilkS")
		)
		(fp_line
			(start -0.889 -1.9304)
			(end 0.889 -1.9304)
			(stroke
				(width 0.1524)
				(type default)
			)
			(layer "F.SilkS")
		)
		(fp_line
			(start 0.762 2.0574)
			(end -0.762 2.0574)
			(stroke
				(width 0.508)
				(type default)
			)
			(layer "F.SilkS")
		)
		(fp_line
			(start 0.889 2.159)
			(end -0.889 2.159)
			(stroke
				(width 0.1524)
				(type default)
			)
			(layer "F.SilkS")
		)
		(fp_line
			(start -0.889 2.159)
			(end -0.889 -1.9304)
			(stroke
				(width 0.1524)
				(type default)
			)
			(layer "F.SilkS")
		)
		(fp_rect
			(start -1.016 2.3114)
			(end 1.016 -2.0066)
			(stroke
				(width 0)
				(type default)
			)
			(fill no)
			(layer "F.CrtYd")
		)
		(fp_poly
			(pts
				(xy -1.016 -2.0066) (xy 1.016 -2.0066) (xy 1.016 2.3114) (xy -1.016 2.3114)
			)
			(stroke
				(width 0)
				(type default)
			)
			(fill no)
			(layer "F.Fab")
		)
		(pad "A" smd rect
			(at 0 -1.143 90)
			(size 0.5588 1.016)
			(layers "F.Cu" "F.Mask" "F.Paste")
			(net "SW_HDD_R9")
		)
		(pad "K" smd rect
			(at 0 1.143 90)
			(size 0.5588 1.016)
			(layers "F.Cu" "F.Mask" "F.Paste")
			(net "SW_HDD_N9")
		)
	)
	(footprint ""
		(layer "F.Cu")
		(at 222.616522 -117.98427 -90)
		(property "Reference" "R1001"
			(at 0 0 270)
			(layer "F.SilkS")
			(hide yes)
			(effects
				(font
					(size 1.27 1.27)
				)
			)
		)
		(property "Value" "100KR2F-L1-GP"
			(at 0.064008 -3.993896 270)
			(unlocked yes)
			(layer "F.Fab")
			(hide yes)
			(effects
				(font
					(size 1.016 1.016)
					(thickness 0.1524)
				)
			)
		)
		(property "Device Type" "R402H16"
			(at 0.064008 -5.517896 270)
			(unlocked yes)
			(layer "F.Fab")
			(hide yes)
			(effects
				(font
					(size 1.016 1.016)
					(thickness 0.1524)
				)
			)
		)
		(duplicate_pad_numbers_are_jumpers no)
		(fp_line
			(start -0.508 -0.9398)
			(end -0.508 0.9398)
			(stroke
				(width 0.1524)
				(type default)
			)
			(layer "F.SilkS")
		)
		(fp_line
			(start 0.508 -0.9398)
			(end -0.508 -0.9398)
			(stroke
				(width 0.1524)
				(type default)
			)
			(layer "F.SilkS")
		)
		(fp_rect
			(start -0.508 0.9398)
			(end 0.508 -0.9398)
			(stroke
				(width 0)
				(type default)
			)
			(fill no)
			(layer "F.CrtYd")
		)
		(fp_rect
			(start -0.508 0.9398)
			(end 0.508 -0.9398)
			(stroke
				(width 0)
				(type default)
			)
			(fill no)
			(layer "F.Fab")
		)
		(pad "1" smd custom
			(at 0 -0.4445 270)
			(size 0.1397 0.1397)
			(layers "F.Cu" "F.Mask" "F.Paste")
			(net "PCIE_COMP_A_TO_SCC_A_RST_0")
			(options
				(clearance outline)
				(anchor circle)
			)
			(primitives
				(gr_poly
					(pts
						(arc
							(start -0.1778 -0.2794)
							(mid -0.249642 -0.249642)
							(end -0.2794 -0.1778)
						)
						(arc
							(start -0.2794 0.1778)
							(mid -0.249642 0.249642)
							(end -0.1778 0.2794)
						)
						(arc
							(start 0.1778 0.2794)
							(mid 0.249642 0.249642)
							(end 0.2794 0.1778)
						)
						(arc
							(start 0.2794 -0.1778)
							(mid 0.249642 -0.249642)
							(end 0.1778 -0.2794)
						)
					)
					(width 0)
					(fill yes)
				)
			)
		)
		(pad "2" smd custom
			(at 0 0.4445 270)
			(size 0.1397 0.1397)
			(layers "F.Cu" "F.Mask" "F.Paste")
			(net "GND")
			(options
				(clearance outline)
				(anchor circle)
			)
			(primitives
				(gr_poly
					(pts
						(arc
							(start -0.1778 -0.2794)
							(mid -0.249642 -0.249642)
							(end -0.2794 -0.1778)
						)
						(arc
							(start -0.2794 0.1778)
							(mid -0.249642 0.249642)
							(end -0.1778 0.2794)
						)
						(arc
							(start 0.1778 0.2794)
							(mid 0.249642 0.249642)
							(end 0.2794 0.1778)
						)
						(arc
							(start 0.2794 -0.1778)
							(mid 0.249642 -0.249642)
							(end 0.1778 -0.2794)
						)
					)
					(width 0)
					(fill yes)
				)
			)
		)
	)
)
